# T6G (Grand Teton) — schematic netlist excerpt (pin names and nets, part order shuffled) for the footprints in the layout excerpt that follows; sources: Cadence DE-HDL packaged netlist, KiCad conversion of 04192023_DAF0TMB3IC0_F0TG_MB_C_brd_V02_OCP.brd

J16  SCONN288_DDR506112002KQ  IO  pkg DDR288S_1-1VXC  page 92
  VIN_BULK0  = P12V_MEM_CPU0
  RFU0  = NC
  VIN_MGMT  = P3V3_AUX
  HSCL  = I3C_SPD_DDRG_CPU0_SCL
  HSDA  = I3C_SPD_DDRG_CPU0_SDA
  VSS0  = GND
  DQ0_A  = M_G_CPU0_SA_DQ<0>
  VSS1  = GND
  DQ1_A  = M_G_CPU0_SA_DQ<1>
  VSS2  = GND
  DQS0_A_T  = M_G_CPU0_SA_DQS_DP<0>
  DQS0_A_C  = M_G_CPU0_SA_DQS_DN<0>
  VSS3  = GND
  DQ4_A  = M_G_CPU0_SA_DQ<4>
  VSS4  = GND
  DQ5_A  = M_G_CPU0_SA_DQ<5>
  VSS5  = GND
  DQ8_A  = M_G_CPU0_SA_DQ<8>
  VSS6  = GND
  DQ9_A  = M_G_CPU0_SA_DQ<9>
  VSS7  = GND
  DQS1_A_T  = M_G_CPU0_SA_DQS_DP<1>
  DQS1_A_C  = M_G_CPU0_SA_DQS_DN<1>
  VSS8  = GND
  DQ12_A  = M_G_CPU0_SA_DQ<12>
  VSS9  = GND
  DQ13_A  = M_G_CPU0_SA_DQ<13>
  VSS10  = GND
  DQ16_A  = M_G_CPU0_SA_DQ<16>
  VSS11  = GND
  DQ17_A  = M_G_CPU0_SA_DQ<17>
  VSS12  = GND
  DQS2_A_T  = M_G_CPU0_SA_DQS_DP<2>
  DQS2_A_C  = M_G_CPU0_SA_DQS_DN<2>
  VSS13  = GND
  DQ20_A  = M_G_CPU0_SA_DQ<20>
  VSS14  = GND
  DQ21_A  = M_G_CPU0_SA_DQ<21>
  VSS15  = GND
  DQ24_A  = M_G_CPU0_SA_DQ<24>
  VSS16  = GND
  DQ25_A  = M_G_CPU0_SA_DQ<25>
  VSS17  = GND
  DQS3_A_T  = M_G_CPU0_SA_DQS_DP<3>
  DQS3_A_C  = M_G_CPU0_SA_DQS_DN<3>
  VSS18  = GND
  DQ28_A  = M_G_CPU0_SA_DQ<28>
  VSS19  = GND
  DQ29_A  = M_G_CPU0_SA_DQ<29>
  VSS20  = GND
  CB0_A  = M_G_CPU0_SA_CB<0>
  VSS21  = GND
  CB1_A  = M_G_CPU0_SA_CB<1>
  VSS22  = GND
  DQS4_A_T  = M_G_CPU0_SA_DQS_DP<4>
  DQS4_A_C  = M_G_CPU0_SA_DQS_DN<4>
  VSS23  = GND
  CB4_A  = M_G_CPU0_SA_CB<4>
  VSS24  = GND
  CB5_A  = M_G_CPU0_SA_CB<5>
  VSS25  = GND
  ALERT_N  = M_G_CPU0_ALERT_N
  VSS26  = GND
  CS0_A_N  = M_G_CPU0_SA_CS_N<0>
  VSS27  = GND
  CA0_A  = M_G_CPU0_SA_CA<0>
  VSS28  = GND
  CA2_A  = M_G_CPU0_SA_CA<2>
  VSS29  = GND
  CA4_A  = M_G_CPU0_SA_CA<4>
  VSS30  = GND
  CA6_A  = M_G_CPU0_SA_CA<6>
  VSS31  = GND
  PAR_A  = M_G_CPU0_SA_PAR
  VSS32  = GND
  CA0_B  = M_G_CPU0_SB_CA<0>
  VSS33  = GND
  CA2_B  = M_G_CPU0_SB_CA<2>
  VSS34  = GND
  CA4_B  = M_G_CPU0_SB_CA<4>
  VSS35  = GND
  CA6_B  = M_G_CPU0_SB_CA<6>
  VSS36  = GND
  CS0_B_N  = M_G_CPU0_SB_CS_N<0>
  VSS37  = GND
  \lbd||rsp_a_n\  = M_G_CPU0_SA_RSP<0>
  \lbs||rsp_b_n\  = M_G_CPU0_SB_RSP<0>
  VSS38  = GND
  CB4_B  = M_G_CPU0_SB_CB<4>
  VSS39  = GND
  CB5_B  = M_G_CPU0_SB_CB<5>
  VSS40  = GND
  \dqs9_b_t||tdqs9_b_t||dbi4_b_n\  = M_G_CPU0_SB_DQS_DP<9>
  \dqs9_b_c||tdqs9_b_c\  = M_G_CPU0_SB_DQS_DN<9>
  VSS41  = GND
  CB0_B  = M_G_CPU0_SB_CB<0>
  VSS42  = GND
  CB1_B  = M_G_CPU0_SB_CB<1>
  VSS43  = GND
  DQ0_B  = M_G_CPU0_SB_DQ<0>
  VSS44  = GND
  DQ1_B  = M_G_CPU0_SB_DQ<1>
  VSS45  = GND
  DQS0_B_T  = M_G_CPU0_SB_DQS_DP<0>
  DQS0_B_C  = M_G_CPU0_SB_DQS_DN<0>
  VSS46  = GND
  DQ4_B  = M_G_CPU0_SB_DQ<4>
  VSS47  = GND
  DQ5_B  = M_G_CPU0_SB_DQ<5>
  VSS48  = GND
  DQ8_B  = M_G_CPU0_SB_DQ<8>
  VSS49  = GND
  DQ9_B  = M_G_CPU0_SB_DQ<9>
  VSS50  = GND
  DQS1_B_T  = M_G_CPU0_SB_DQS_DP<1>
  DQS1_B_C  = M_G_CPU0_SB_DQS_DN<1>
  VSS51  = GND
  DQ12_B  = M_G_CPU0_SB_DQ<12>
  VSS52  = GND
  DQ13_B  = M_G_CPU0_SB_DQ<13>
  VSS53  = GND
  DQ16_B  = M_G_CPU0_SB_DQ<16>
  VSS54  = GND
  DQ17_B  = M_G_CPU0_SB_DQ<17>
  VSS55  = GND
  DQS2_B_T  = M_G_CPU0_SB_DQS_DP<2>
  DQS2_B_C  = M_G_CPU0_SB_DQS_DN<2>
  VSS56  = GND
  DQ20_B  = M_G_CPU0_SB_DQ<20>
  VSS57  = GND
  DQ21_B  = M_G_CPU0_SB_DQ<21>
  VSS58  = GND
  DQ24_B  = M_G_CPU0_SB_DQ<24>
  VSS59  = GND
  DQ25_B  = M_G_CPU0_SB_DQ<25>
  VSS60  = GND
  DQS3_B_T  = M_G_CPU0_SB_DQS_DP<3>
  DQS3_B_C  = M_G_CPU0_SB_DQS_DN<3>
  VSS61  = GND
  DQ28_B  = M_G_CPU0_SB_DQ<28>
  VSS62  = GND
  DQ29_B  = M_G_CPU0_SB_DQ<29>
  VSS63  = GND
  RFU1  = NC
  VIN_BULK1  = P12V_MEM_CPU0
  VIN_BULK2  = P12V_MEM_CPU0
  \pwr_good||fail_n\  = PWRGD_CHG_CPU0_DIMM0
  HAS  = PD_CHG_CPU0_DIMM0_SAA
  RFU2  = NC
  RFU3  = NC
  VSS64  = GND
  DQ2_A  = M_G_CPU0_SA_DQ<2>
  VSS65  = GND
  DQ3_A  = M_G_CPU0_SA_DQ<3>
  VSS66  = GND
  \dqs5_a_c||tdqs5_a_c||dqs5_a_t||tdqs5_a_t\  = M_G_CPU0_SA_DQS_DN<5>
  \dqs5_a_t||tdqs5_a_t\  = M_G_CPU0_SA_DQS_DP<5>
  VSS67  = GND
  DQ6_A  = M_G_CPU0_SA_DQ<6>
  VSS68  = GND
  DQ7_A  = M_G_CPU0_SA_DQ<7>
  VSS69  = GND
  DQ10_A  = M_G_CPU0_SA_DQ<10>
  VSS70  = GND
  DQ11_A  = M_G_CPU0_SA_DQ<11>
  VSS71  = GND
  \dqs6_a_c||tdqs6_a_c||dqs6_a_t||tdqs6_a_t\  = M_G_CPU0_SA_DQS_DN<6>
  \dqs6_a_t||tdqs6_a_t\  = M_G_CPU0_SA_DQS_DP<6>
  VSS72  = GND
  DQ14_A  = M_G_CPU0_SA_DQ<14>
  VSS73  = GND
  DQ15_A  = M_G_CPU0_SA_DQ<15>
  VSS74  = GND
  DQ18_A  = M_G_CPU0_SA_DQ<18>
  VSS75  = GND
  DQ19_A  = M_G_CPU0_SA_DQ<19>
  VSS76  = GND
  \dqs7_a_c||tdqs7_a_c\  = M_G_CPU0_SA_DQS_DN<7>
  \dqs7_a_t||tdqs7_a_t\  = M_G_CPU0_SA_DQS_DP<7>
  VSS77  = GND
  DQ22_A  = M_G_CPU0_SA_DQ<22>
  VSS78  = GND
  DQ23_A  = M_G_CPU0_SA_DQ<23>
  VSS79  = GND
  DQ26_A  = M_G_CPU0_SA_DQ<26>
  VSS80  = GND
  DQ27_A  = M_G_CPU0_SA_DQ<27>
  VSS81  = GND
  \dqs8_a_c||tdqs8_a_c\  = M_G_CPU0_SA_DQS_DN<8>
  \dqs8_a_t||tdqs8_a_t\  = M_G_CPU0_SA_DQS_DP<8>
  VSS82  = GND
  DQ30_A  = M_G_CPU0_SA_DQ<30>
  VSS83  = GND
  DQ31_A  = M_G_CPU0_SA_DQ<31>
  VSS84  = GND
  CB2_A  = M_G_CPU0_SA_CB<2>
  VSS85  = GND
  CB3_A  = M_G_CPU0_SA_CB<3>
  VSS86  = GND
  \dqs9_a_c||tdqs9_a_c\  = M_G_CPU0_SA_DQS_DN<9>
  \dqs9_a_t||tdqs9_a_t\  = M_G_CPU0_SA_DQS_DP<9>
  VSS87  = GND
  CB6_A  = M_G_CPU0_SA_CB<6>
  VSS88  = GND
  CB7_A  = M_G_CPU0_SA_CB<7>
  VSS89  = GND
  RESET_N  = M_G_CPU0_RESET_N
  VSS90  = GND
  CS1_A_N  = M_G_CPU0_SA_CS_N<1>
  VSS91  = GND
  CA1_A  = M_G_CPU0_SA_CA<1>
  VSS92  = GND
  CA3_A  = M_G_CPU0_SA_CA<3>
  VSS93  = GND
  CA5_A  = M_G_CPU0_SA_CA<5>
  VSS94  = GND
  CK_T  = M_G_CPU0_CLK_DP<0>
  CK_C  = M_G_CPU0_CLK_DN<0>
  VSS95  = GND
  RFU4  = NC
  CA1_B  = M_G_CPU0_SB_CA<1>
  VSS96  = GND
  CA3_B  = M_G_CPU0_SB_CA<3>
  VSS97  = GND
  CA5_B  = M_G_CPU0_SB_CA<5>
  VSS98  = GND
  PAR_B  = M_G_CPU0_SB_PAR
  VSS99  = GND
  CS1_B_N  = M_G_CPU0_SB_CS_N<1>
  VSS100  = GND
  RFU5  = NC
  RFU6  = NC
  VSS101  = GND
  CB6_B  = M_G_CPU0_SB_CB<6>
  VSS102  = GND
  CB7_B  = M_G_CPU0_SB_CB<7>
  VSS103  = GND
  DQS4_B_C  = M_G_CPU0_SB_DQS_DN<4>
  DQS4_B_T  = M_G_CPU0_SB_DQS_DP<4>
  VSS104  = GND
  CB2_B  = M_G_CPU0_SB_CB<2>
  VSS105  = GND
  CB3_B  = M_G_CPU0_SB_CB<3>
  VSS106  = GND
  DQ2_B  = M_G_CPU0_SB_DQ<2>
  VSS107  = GND
  DQ3_B  = M_G_CPU0_SB_DQ<3>
  VSS108  = GND
  \dqs5_b_c||tdqs5_b_c\  = M_G_CPU0_SB_DQS_DN<5>
  \dqs5_b_t||tdqs5_b_t\  = M_G_CPU0_SB_DQS_DP<5>
  VSS109  = GND
  DQ6_B  = M_G_CPU0_SB_DQ<6>
  VSS110  = GND
  DQ7_B  = M_G_CPU0_SB_DQ<7>
  VSS111  = GND
  DQ10_B  = M_G_CPU0_SB_DQ<10>
  VSS112  = GND
  DQ11_B  = M_G_CPU0_SB_DQ<11>
  VSS113  = GND
  \dqs6_b_c||tdqs6_b_c\  = M_G_CPU0_SB_DQS_DN<6>
  \dqs6_b_t||tdqs6_b_t\  = M_G_CPU0_SB_DQS_DP<6>
  VSS114  = GND
  DQ14_B  = M_G_CPU0_SB_DQ<14>
  VSS115  = GND
  DQ15_B  = M_G_CPU0_SB_DQ<15>
  VSS116  = GND
  DQ18_B  = M_G_CPU0_SB_DQ<18>
  VSS117  = GND
  DQ19_B  = M_G_CPU0_SB_DQ<19>
  VSS118  = GND
  \dqs7_b_c||tdqs7_b_c\  = M_G_CPU0_SB_DQS_DN<7>
  \dqs7_b_t||tdqs7_b_t\  = M_G_CPU0_SB_DQS_DP<7>
  VSS119  = GND
  DQ22_B  = M_G_CPU0_SB_DQ<22>
  VSS120  = GND
  DQ23_B  = M_G_CPU0_SB_DQ<23>
  VSS121  = GND
  DQ26_B  = M_G_CPU0_SB_DQ<26>
  VSS122  = GND
  DQ27_B  = M_G_CPU0_SB_DQ<27>
  VSS123  = GND
  \dqs8_b_c||tdqs8_b_c\  = M_G_CPU0_SB_DQS_DN<8>
  \dqs8_b_t||tdqs8_b_t\  = M_G_CPU0_SB_DQS_DP<8>
  VSS124  = GND
  DQ30_B  = M_G_CPU0_SB_DQ<30>
  VSS125  = GND
  DQ31_B  = M_G_CPU0_SB_DQ<31>
  VSS126  = GND
  G1  = GND
  G2  = GND
  G3  = GND

(kicad_pcb
	(version 20260206)
	(generator "pcbnew")
	(generator_version "10.0")
	(general
		(thickness 1.6)
		(legacy_teardrops no)
	)
	(paper "A4")
	(title_block
		(title "04192023_DAF0TMB3IC0_F0TG_MB_C_brd_V02_OCP.brd")
		(comment 1 "Grand Teton / footprint 1808 of 8354 (J16), pads 231-276 of 291")
	)
	(layers
		(0 "F.Cu" signal "TOP")
		(4 "In1.Cu" signal "GND")
		(6 "In2.Cu" signal "IN1")
		(8 "In3.Cu" signal "GND1")
		(10 "In4.Cu" signal "IN2")
		(12 "In5.Cu" signal "GND2")
		(14 "In6.Cu" signal "IN3")
		(16 "In7.Cu" signal "GND3")
		(18 "In8.Cu" signal "VCC")
		(20 "In9.Cu" signal "VCC1")
		(22 "In10.Cu" signal "GND4")
		(24 "In11.Cu" signal "IN4")
		(26 "In12.Cu" signal "GND5")
		(28 "In13.Cu" signal "IN5")
		(30 "In14.Cu" signal "GND6")
		(32 "In15.Cu" signal "IN6")
		(34 "In16.Cu" signal "GND7")
		(2 "B.Cu" signal "BOTTOM")
		(9 "F.Adhes" user "F.Adhesive")
		(11 "B.Adhes" user "B.Adhesive")
		(13 "F.Paste" user "Package Geometry/Pastemask Top")
		(15 "B.Paste" user "Package Geometry/Pastemask Bottom")
		(5 "F.SilkS" user "Ref Des/Silkscreen Top")
		(7 "B.SilkS" user "Ref Des/Silkscreen Bottom")
		(1 "F.Mask" user "Board Geometry/Soldermask Top")
		(3 "B.Mask" user "Board Geometry/Soldermask Bottom")
		(17 "Dwgs.User" user "User.Drawings")
		(19 "Cmts.User" user "User.Comments")
		(21 "Eco1.User" user "User.Eco1")
		(23 "Eco2.User" user "User.Eco2")
		(25 "Edge.Cuts" user "Board Geometry/Outline")
		(27 "Margin" user)
		(31 "F.CrtYd" user "Package Geometry/Place Bound Top")
		(29 "B.CrtYd" user "Package Geometry/Place Bound Bottom")
		(35 "F.Fab" user "Ref Des/Assembly Top")
		(33 "B.Fab" user "Ref Des/Assembly Bottom")
	)
	(footprint ""
		(layer "F.Cu")
		(at 414.418018 -255.560068 180)
		(property "Reference" "J16"
			(at 1.474216 81.889092 0)
			(unlocked yes)
			(layer "F.SilkS")
			(effects
				(font
					(size 0.7874 0.5842)
					(thickness 0.1524)
				)
			)
		)
		(property "Value" ""
			(at 0 0 180)
			(layer "F.Fab")
			(effects
				(font
					(size 1.27 1.27)
				)
			)
		)
		(duplicate_pad_numbers_are_jumpers no)
		(pad "231" smd rect
			(at 2.050034 14.875002 90)
			(size 0.519938 1.4986)
			(layers "F.Cu" "F.Mask" "F.Paste")
			(net "Net_2338")
		)
		(pad "232" smd rect
			(at 2.050034 15.724886 90)
			(size 0.519938 1.4986)
			(layers "F.Cu" "F.Mask" "F.Paste")
			(net "Net_2339")
		)
		(pad "233" smd rect
			(at 2.050034 16.575024 90)
			(size 0.519938 1.4986)
			(layers "F.Cu" "F.Mask" "F.Paste")
			(net "GND")
		)
		(pad "234" smd rect
			(at 2.050034 17.424908 90)
			(size 0.519938 1.4986)
			(layers "F.Cu" "F.Mask" "F.Paste")
			(net "M_G_CPU0_SB_CB<6>")
		)
		(pad "235" smd rect
			(at 2.050034 18.275046 90)
			(size 0.519938 1.4986)
			(layers "F.Cu" "F.Mask" "F.Paste")
			(net "GND")
		)
		(pad "236" smd rect
			(at 2.050034 19.12493 90)
			(size 0.519938 1.4986)
			(layers "F.Cu" "F.Mask" "F.Paste")
			(net "M_G_CPU0_SB_CB<7>")
		)
		(pad "237" smd rect
			(at 2.050034 19.975068 90)
			(size 0.519938 1.4986)
			(layers "F.Cu" "F.Mask" "F.Paste")
			(net "GND")
		)
		(pad "238" smd rect
			(at 2.050034 20.824952 90)
			(size 0.519938 1.4986)
			(layers "F.Cu" "F.Mask" "F.Paste")
			(net "M_G_CPU0_SB_DQS_DN<4>")
		)
		(pad "239" smd rect
			(at 2.050034 21.67509 90)
			(size 0.519938 1.4986)
			(layers "F.Cu" "F.Mask" "F.Paste")
			(net "M_G_CPU0_SB_DQS_DP<4>")
		)
		(pad "240" smd rect
			(at 2.050034 22.524974 90)
			(size 0.519938 1.4986)
			(layers "F.Cu" "F.Mask" "F.Paste")
			(net "GND")
		)
		(pad "241" smd rect
			(at 2.050034 23.375112 90)
			(size 0.519938 1.4986)
			(layers "F.Cu" "F.Mask" "F.Paste")
			(net "M_G_CPU0_SB_CB<2>")
		)
		(pad "242" smd rect
			(at 2.050034 24.224996 90)
			(size 0.519938 1.4986)
			(layers "F.Cu" "F.Mask" "F.Paste")
			(net "GND")
		)
		(pad "243" smd rect
			(at 2.050034 25.07488 90)
			(size 0.519938 1.4986)
			(layers "F.Cu" "F.Mask" "F.Paste")
			(net "M_G_CPU0_SB_CB<3>")
		)
		(pad "244" smd rect
			(at 2.050034 25.925018 90)
			(size 0.519938 1.4986)
			(layers "F.Cu" "F.Mask" "F.Paste")
			(net "GND")
		)
		(pad "245" smd rect
			(at 2.050034 26.774902 90)
			(size 0.519938 1.4986)
			(layers "F.Cu" "F.Mask" "F.Paste")
			(net "M_G_CPU0_SB_DQ<2>")
		)
		(pad "246" smd rect
			(at 2.050034 27.62504 90)
			(size 0.519938 1.4986)
			(layers "F.Cu" "F.Mask" "F.Paste")
			(net "GND")
		)
		(pad "247" smd rect
			(at 2.050034 28.474924 90)
			(size 0.519938 1.4986)
			(layers "F.Cu" "F.Mask" "F.Paste")
			(net "M_G_CPU0_SB_DQ<3>")
		)
		(pad "248" smd rect
			(at 2.050034 29.325062 90)
			(size 0.519938 1.4986)
			(layers "F.Cu" "F.Mask" "F.Paste")
			(net "GND")
		)
		(pad "249" smd rect
			(at 2.050034 30.174946 90)
			(size 0.519938 1.4986)
			(layers "F.Cu" "F.Mask" "F.Paste")
			(net "M_G_CPU0_SB_DQS_DN<5>")
		)
		(pad "250" smd rect
			(at 2.050034 31.025084 90)
			(size 0.519938 1.4986)
			(layers "F.Cu" "F.Mask" "F.Paste")
			(net "M_G_CPU0_SB_DQS_DP<5>")
		)
		(pad "251" smd rect
			(at 2.050034 31.874968 90)
			(size 0.519938 1.4986)
			(layers "F.Cu" "F.Mask" "F.Paste")
			(net "GND")
		)
		(pad "252" smd rect
			(at 2.050034 32.725106 90)
			(size 0.519938 1.4986)
			(layers "F.Cu" "F.Mask" "F.Paste")
			(net "M_G_CPU0_SB_DQ<6>")
		)
		(pad "253" smd rect
			(at 2.050034 33.57499 90)
			(size 0.519938 1.4986)
			(layers "F.Cu" "F.Mask" "F.Paste")
			(net "GND")
		)
		(pad "254" smd rect
			(at 2.050034 34.425128 90)
			(size 0.519938 1.4986)
			(layers "F.Cu" "F.Mask" "F.Paste")
			(net "M_G_CPU0_SB_DQ<7>")
		)
		(pad "255" smd rect
			(at 2.050034 35.275012 90)
			(size 0.519938 1.4986)
			(layers "F.Cu" "F.Mask" "F.Paste")
			(net "GND")
		)
		(pad "256" smd rect
			(at 2.050034 36.124896 90)
			(size 0.519938 1.4986)
			(layers "F.Cu" "F.Mask" "F.Paste")
			(net "M_G_CPU0_SB_DQ<10>")
		)
		(pad "257" smd rect
			(at 2.050034 36.975034 90)
			(size 0.519938 1.4986)
			(layers "F.Cu" "F.Mask" "F.Paste")
			(net "GND")
		)
		(pad "258" smd rect
			(at 2.050034 37.824918 90)
			(size 0.519938 1.4986)
			(layers "F.Cu" "F.Mask" "F.Paste")
			(net "M_G_CPU0_SB_DQ<11>")
		)
		(pad "259" smd rect
			(at 2.050034 38.675056 90)
			(size 0.519938 1.4986)
			(layers "F.Cu" "F.Mask" "F.Paste")
			(net "GND")
		)
		(pad "260" smd rect
			(at 2.050034 39.52494 90)
			(size 0.519938 1.4986)
			(layers "F.Cu" "F.Mask" "F.Paste")
			(net "M_G_CPU0_SB_DQS_DN<6>")
		)
		(pad "261" smd rect
			(at 2.050034 40.375078 90)
			(size 0.519938 1.4986)
			(layers "F.Cu" "F.Mask" "F.Paste")
			(net "M_G_CPU0_SB_DQS_DP<6>")
		)
		(pad "262" smd rect
			(at 2.050034 41.224962 90)
			(size 0.519938 1.4986)
			(layers "F.Cu" "F.Mask" "F.Paste")
			(net "GND")
		)
		(pad "263" smd rect
			(at 2.050034 42.0751 90)
			(size 0.519938 1.4986)
			(layers "F.Cu" "F.Mask" "F.Paste")
			(net "M_G_CPU0_SB_DQ<14>")
		)
		(pad "264" smd rect
			(at 2.050034 42.924984 90)
			(size 0.519938 1.4986)
			(layers "F.Cu" "F.Mask" "F.Paste")
			(net "GND")
		)
		(pad "265" smd rect
			(at 2.050034 43.775122 90)
			(size 0.519938 1.4986)
			(layers "F.Cu" "F.Mask" "F.Paste")
			(net "M_G_CPU0_SB_DQ<15>")
		)
		(pad "266" smd rect
			(at 2.050034 44.625006 90)
			(size 0.519938 1.4986)
			(layers "F.Cu" "F.Mask" "F.Paste")
			(net "GND")
		)
		(pad "267" smd rect
			(at 2.050034 45.47489 90)
			(size 0.519938 1.4986)
			(layers "F.Cu" "F.Mask" "F.Paste")
			(net "M_G_CPU0_SB_DQ<18>")
		)
		(pad "268" smd rect
			(at 2.050034 46.325028 90)
			(size 0.519938 1.4986)
			(layers "F.Cu" "F.Mask" "F.Paste")
			(net "GND")
		)
		(pad "269" smd rect
			(at 2.050034 47.174912 90)
			(size 0.519938 1.4986)
			(layers "F.Cu" "F.Mask" "F.Paste")
			(net "M_G_CPU0_SB_DQ<19>")
		)
		(pad "270" smd rect
			(at 2.050034 48.02505 90)
			(size 0.519938 1.4986)
			(layers "F.Cu" "F.Mask" "F.Paste")
			(net "GND")
		)
		(pad "271" smd rect
			(at 2.050034 48.874934 90)
			(size 0.519938 1.4986)
			(layers "F.Cu" "F.Mask" "F.Paste")
			(net "M_G_CPU0_SB_DQS_DN<7>")
		)
		(pad "272" smd rect
			(at 2.050034 49.725072 90)
			(size 0.519938 1.4986)
			(layers "F.Cu" "F.Mask" "F.Paste")
			(net "M_G_CPU0_SB_DQS_DP<7>")
		)
		(pad "273" smd rect
			(at 2.050034 50.574956 90)
			(size 0.519938 1.4986)
			(layers "F.Cu" "F.Mask" "F.Paste")
			(net "GND")
		)
		(pad "274" smd rect
			(at 2.050034 51.425094 90)
			(size 0.519938 1.4986)
			(layers "F.Cu" "F.Mask" "F.Paste")
			(net "M_G_CPU0_SB_DQ<22>")
		)
		(pad "275" smd rect
			(at 2.050034 52.274978 90)
			(size 0.519938 1.4986)
			(layers "F.Cu" "F.Mask" "F.Paste")
			(net "GND")
		)
		(pad "276" smd rect
			(at 2.050034 53.125116 90)
			(size 0.519938 1.4986)
			(layers "F.Cu" "F.Mask" "F.Paste")
			(net "M_G_CPU0_SB_DQ<23>")
		)
	)
)
